# T6G (Grand Teton) — schematic netlist excerpt (pin names and nets, part order shuffled) for the footprints in the layout excerpt that follows; sources: Cadence DE-HDL packaged netlist, KiCad conversion of 04192023_DAF0TMB3IC0_F0TG_MB_C_brd_V02_OCP.brd

C2495  Q_CAP  22UF 4V 20% X6S  pkg C0402  page 74 : A = PVDD11_S3_P1 ; B = GND
C2561  Q_CAP  22UF 4V 20% X6S  pkg C0402  page 70 : A = PVDDCR_SOC_P0 ; B = GND
PC294_3  Q_CAP  22UF 16V 20% X6S  pkg C0805  page 212 : A = SW_P12V_AUX_PVDDCR_CPU0_P1_FLT ; B = GND

(kicad_pcb
	(version 20260206)
	(generator "pcbnew")
	(generator_version "10.0")
	(general
		(thickness 1.6)
		(legacy_teardrops no)
	)
	(paper "A4")
	(title_block
		(title "04192023_DAF0TMB3IC0_F0TG_MB_C_brd_V02_OCP.brd")
		(comment 1 "Grand Teton / footprints 7463-7465 of 8354")
	)
	(layers
		(0 "F.Cu" signal "TOP")
		(4 "In1.Cu" signal "GND")
		(6 "In2.Cu" signal "IN1")
		(8 "In3.Cu" signal "GND1")
		(10 "In4.Cu" signal "IN2")
		(12 "In5.Cu" signal "GND2")
		(14 "In6.Cu" signal "IN3")
		(16 "In7.Cu" signal "GND3")
		(18 "In8.Cu" signal "VCC")
		(20 "In9.Cu" signal "VCC1")
		(22 "In10.Cu" signal "GND4")
		(24 "In11.Cu" signal "IN4")
		(26 "In12.Cu" signal "GND5")
		(28 "In13.Cu" signal "IN5")
		(30 "In14.Cu" signal "GND6")
		(32 "In15.Cu" signal "IN6")
		(34 "In16.Cu" signal "GND7")
		(2 "B.Cu" signal "BOTTOM")
		(9 "F.Adhes" user "F.Adhesive")
		(11 "B.Adhes" user "B.Adhesive")
		(13 "F.Paste" user "Package Geometry/Pastemask Top")
		(15 "B.Paste" user "Package Geometry/Pastemask Bottom")
		(5 "F.SilkS" user "Ref Des/Silkscreen Top")
		(7 "B.SilkS" user "Ref Des/Silkscreen Bottom")
		(1 "F.Mask" user "Board Geometry/Soldermask Top")
		(3 "B.Mask" user "Board Geometry/Soldermask Bottom")
		(17 "Dwgs.User" user "User.Drawings")
		(19 "Cmts.User" user "User.Comments")
		(21 "Eco1.User" user "User.Eco1")
		(23 "Eco2.User" user "User.Eco2")
		(25 "Edge.Cuts" user "Board Geometry/Outline")
		(27 "Margin" user)
		(31 "F.CrtYd" user "Package Geometry/Place Bound Top")
		(29 "B.CrtYd" user "Package Geometry/Place Bound Bottom")
		(35 "F.Fab" user "Ref Des/Assembly Top")
		(33 "B.Fab" user "Ref Des/Assembly Bottom")
	)
	(footprint ""
		(layer "B.Cu")
		(at 97.853754 -178.886612 90)
		(property "Reference" "PC294_3"
			(at 0 0 90)
			(layer "B.SilkS")
			(hide yes)
			(effects
				(font
					(size 1.27 1.27)
				)
				(justify mirror)
			)
		)
		(property "Value" ""
			(at 0 0 90)
			(layer "B.Fab")
			(effects
				(font
					(size 1.27 1.27)
				)
				(justify mirror)
			)
		)
		(duplicate_pad_numbers_are_jumpers no)
		(fp_line
			(start 1.524 -0.762)
			(end -1.524 -0.762)
			(stroke
				(width 0.1524)
				(type default)
			)
			(layer "B.SilkS")
		)
		(fp_line
			(start -1.524 -0.762)
			(end -1.524 0.762)
			(stroke
				(width 0.1524)
				(type default)
			)
			(layer "B.SilkS")
		)
		(fp_line
			(start 1.524 0.762)
			(end 1.524 -0.762)
			(stroke
				(width 0.1524)
				(type default)
			)
			(layer "B.SilkS")
		)
		(fp_line
			(start -1.524 0.762)
			(end 1.524 0.762)
			(stroke
				(width 0.1524)
				(type default)
			)
			(layer "B.SilkS")
		)
		(fp_line
			(start 1.1049 -0.724916)
			(end 1.1049 0.724916)
			(stroke
				(width 0.1)
				(type default)
			)
			(layer "B.Fab")
		)
		(fp_line
			(start -1.1049 -0.724916)
			(end 1.1049 -0.724916)
			(stroke
				(width 0.1)
				(type default)
			)
			(layer "B.Fab")
		)
		(fp_line
			(start 1.1049 0.724916)
			(end -1.1049 0.724916)
			(stroke
				(width 0.1)
				(type default)
			)
			(layer "B.Fab")
		)
		(fp_line
			(start -1.1049 0.724916)
			(end -1.1049 -0.724916)
			(stroke
				(width 0.1)
				(type default)
			)
			(layer "B.Fab")
		)
		(pad "1" smd rect
			(at 0.889 0 90)
			(size 1.016 1.27)
			(layers "B.Cu" "B.Mask" "B.Paste")
			(net "SW_P12V_AUX_PVDDCR_CPU0_P1_FLT")
		)
		(pad "2" smd rect
			(at -0.889 0 90)
			(size 1.016 1.27)
			(layers "B.Cu" "B.Mask" "B.Paste")
			(net "GND")
		)
	)
	(footprint ""
		(layer "B.Cu")
		(at 102.656386 -264.354564)
		(property "Reference" "C2495"
			(at 0 0 0)
			(layer "B.SilkS")
			(hide yes)
			(effects
				(font
					(size 1.27 1.27)
				)
				(justify mirror)
			)
		)
		(property "Value" ""
			(at 0 0 0)
			(layer "B.Fab")
			(effects
				(font
					(size 1.27 1.27)
				)
				(justify mirror)
			)
		)
		(duplicate_pad_numbers_are_jumpers no)
		(fp_line
			(start -0.7874 -0.4064)
			(end -0.7874 0.4064)
			(stroke
				(width 0.1524)
				(type default)
			)
			(layer "B.SilkS")
		)
		(fp_line
			(start -0.7874 0.4064)
			(end 0.7874 0.4064)
			(stroke
				(width 0.1524)
				(type default)
			)
			(layer "B.SilkS")
		)
		(fp_line
			(start 0.7874 -0.4064)
			(end -0.7874 -0.4064)
			(stroke
				(width 0.1524)
				(type default)
			)
			(layer "B.SilkS")
		)
		(fp_line
			(start 0.7874 0.4064)
			(end 0.7874 -0.4064)
			(stroke
				(width 0.1524)
				(type default)
			)
			(layer "B.SilkS")
		)
		(fp_line
			(start -0.67945 -0.3048)
			(end -0.67945 0.3048)
			(stroke
				(width 0.1)
				(type default)
			)
			(layer "B.Fab")
		)
		(fp_line
			(start -0.67945 0.3048)
			(end -0.120396 0.3048)
			(stroke
				(width 0.1)
				(type default)
			)
			(layer "B.Fab")
		)
		(fp_line
			(start -0.12065 -0.3048)
			(end -0.67945 -0.3048)
			(stroke
				(width 0.1)
				(type default)
			)
			(layer "B.Fab")
		)
		(fp_line
			(start -0.12065 -0.2794)
			(end -0.12065 -0.3048)
			(stroke
				(width 0.1)
				(type default)
			)
			(layer "B.Fab")
		)
		(fp_line
			(start -0.120396 0.2794)
			(end 0.12065 0.2794)
			(stroke
				(width 0.1)
				(type default)
			)
			(layer "B.Fab")
		)
		(fp_line
			(start -0.120396 0.3048)
			(end -0.120396 0.2794)
			(stroke
				(width 0.1)
				(type default)
			)
			(layer "B.Fab")
		)
		(fp_line
			(start 0.12065 -0.305054)
			(end 0.12065 -0.2794)
			(stroke
				(width 0.1)
				(type default)
			)
			(layer "B.Fab")
		)
		(fp_line
			(start 0.12065 -0.2794)
			(end -0.12065 -0.2794)
			(stroke
				(width 0.1)
				(type default)
			)
			(layer "B.Fab")
		)
		(fp_line
			(start 0.12065 0.2794)
			(end 0.12065 0.3048)
			(stroke
				(width 0.1)
				(type default)
			)
			(layer "B.Fab")
		)
		(fp_line
			(start 0.12065 0.3048)
			(end 0.67945 0.3048)
			(stroke
				(width 0.1)
				(type default)
			)
			(layer "B.Fab")
		)
		(fp_line
			(start 0.67945 -0.305054)
			(end 0.12065 -0.305054)
			(stroke
				(width 0.1)
				(type default)
			)
			(layer "B.Fab")
		)
		(fp_line
			(start 0.67945 0.3048)
			(end 0.67945 -0.305054)
			(stroke
				(width 0.1)
				(type default)
			)
			(layer "B.Fab")
		)
		(pad "1" smd circle
			(at 0.40005 0 180)
			(size 0 0)
			(layers "B.Cu" "B.Mask" "B.Paste")
			(net "PVDD11_S3_P1")
		)
		(pad "2" smd circle
			(at -0.40005 0 180)
			(size 0 0)
			(layers "B.Cu" "B.Mask" "B.Paste")
			(net "GND")
		)
	)
	(footprint ""
		(layer "B.Cu")
		(at 350.204278 -254.507492 -60)
		(property "Reference" "C2561"
			(at 0 0 120)
			(layer "B.SilkS")
			(hide yes)
			(effects
				(font
					(size 1.27 1.27)
				)
				(justify mirror)
			)
		)
		(property "Value" ""
			(at 0 0 120)
			(layer "B.Fab")
			(effects
				(font
					(size 1.27 1.27)
				)
				(justify mirror)
			)
		)
		(duplicate_pad_numbers_are_jumpers no)
		(fp_line
			(start -0.787516 0.406438)
			(end 0.787425 0.40652)
			(stroke
				(width 0.1524)
				(type default)
			)
			(layer "B.SilkS")
		)
		(fp_line
			(start -0.787425 -0.40652)
			(end -0.787516 0.406438)
			(stroke
				(width 0.1524)
				(type default)
			)
			(layer "B.SilkS")
		)
		(fp_line
			(start 0.787425 0.40652)
			(end 0.787516 -0.406438)
			(stroke
				(width 0.1524)
				(type default)
			)
			(layer "B.SilkS")
		)
		(fp_line
			(start 0.787516 -0.406438)
			(end -0.787425 -0.40652)
			(stroke
				(width 0.1524)
				(type default)
			)
			(layer "B.SilkS")
		)
		(fp_line
			(start -0.679568 0.304811)
			(end -0.120258 0.304812)
			(stroke
				(width 0.1)
				(type default)
			)
			(layer "B.Fab")
		)
		(fp_line
			(start -0.120258 0.304812)
			(end -0.120334 0.279545)
			(stroke
				(width 0.1)
				(type default)
			)
			(layer "B.Fab")
		)
		(fp_line
			(start -0.120334 0.279545)
			(end 0.120587 0.279326)
			(stroke
				(width 0.1)
				(type default)
			)
			(layer "B.Fab")
		)
		(fp_line
			(start 0.120536 0.304813)
			(end 0.6795 0.304908)
			(stroke
				(width 0.1)
				(type default)
			)
			(layer "B.Fab")
		)
		(fp_line
			(start 0.120587 0.279326)
			(end 0.120536 0.304813)
			(stroke
				(width 0.1)
				(type default)
			)
			(layer "B.Fab")
		)
		(fp_line
			(start -0.6795 -0.304908)
			(end -0.679568 0.304811)
			(stroke
				(width 0.1)
				(type default)
			)
			(layer "B.Fab")
		)
		(fp_line
			(start 0.6795 0.304908)
			(end 0.679475 -0.305158)
			(stroke
				(width 0.1)
				(type default)
			)
			(layer "B.Fab")
		)
		(fp_line
			(start -0.120587 -0.279326)
			(end -0.120536 -0.304813)
			(stroke
				(width 0.1)
				(type default)
			)
			(layer "B.Fab")
		)
		(fp_line
			(start -0.120536 -0.304813)
			(end -0.6795 -0.304908)
			(stroke
				(width 0.1)
				(type default)
			)
			(layer "B.Fab")
		)
		(fp_line
			(start 0.120554 -0.279418)
			(end -0.120587 -0.279326)
			(stroke
				(width 0.1)
				(type default)
			)
			(layer "B.Fab")
		)
		(fp_line
			(start 0.120732 -0.305125)
			(end 0.120554 -0.279418)
			(stroke
				(width 0.1)
				(type default)
			)
			(layer "B.Fab")
		)
		(fp_line
			(start 0.679475 -0.305158)
			(end 0.120732 -0.305125)
			(stroke
				(width 0.1)
				(type default)
			)
			(layer "B.Fab")
		)
		(pad "1" smd circle
			(at 0.40005 0 120)
			(size 0 0)
			(layers "B.Cu" "B.Mask" "B.Paste")
			(net "PVDDCR_SOC_P0")
		)
		(pad "2" smd circle
			(at -0.40005 0 120)
			(size 0 0)
			(layers "B.Cu" "B.Mask" "B.Paste")
			(net "GND")
		)
	)
)
